# SCM (Grand Teton) — schematic netlist excerpt (pin names and nets, part order shuffled) for the footprints in the layout excerpt that follows; sources: Cadence DE-HDL packaged netlist, KiCad conversion of 12092022_DA0F0TMDCD0_F0T_Management_Board_D_brd_V3_OCP.brd

R112  Q_RES  33.2 1% CHIP  pkg 0402LF  page 13 : A = FM_BIOS_DEBUG_EN_R_N ; B = FM_BIOS_DEBUG_EN_N
R747  Q_RES  0 5% CHIP  pkg 0402LF  page 36 : A = FM_BMC_CRASHLOG_TRIG_N ; B = FM_BMC_CRASHLOG_TRIG_R2_N

(kicad_pcb
	(version 20260206)
	(generator "pcbnew")
	(generator_version "10.0")
	(general
		(thickness 1.6)
		(legacy_teardrops no)
	)
	(paper "A4")
	(title_block
		(title "12092022_DA0F0TMDCD0_F0T_Management_Board_D_brd_V3_OCP.brd")
		(comment 1 "Grand Teton / footprints 718-719 of 1440")
	)
	(layers
		(0 "F.Cu" signal "TOP")
		(4 "In1.Cu" signal "GND")
		(6 "In2.Cu" signal "IN1")
		(8 "In3.Cu" signal "GND1")
		(10 "In4.Cu" signal "IN2")
		(12 "In5.Cu" signal "VCC")
		(14 "In6.Cu" signal "VCC1")
		(16 "In7.Cu" signal "IN3")
		(18 "In8.Cu" signal "GND2")
		(20 "In9.Cu" signal "IN4")
		(22 "In10.Cu" signal "GND3")
		(2 "B.Cu" signal "BOTTOM")
		(9 "F.Adhes" user "F.Adhesive")
		(11 "B.Adhes" user "B.Adhesive")
		(13 "F.Paste" user "Package Geometry/Pastemask Top")
		(15 "B.Paste" user "Package Geometry/Pastemask Bottom")
		(5 "F.SilkS" user "Ref Des/Silkscreen Top")
		(7 "B.SilkS" user "Ref Des/Silkscreen Bottom")
		(1 "F.Mask" user "Board Geometry/Soldermask Top")
		(3 "B.Mask" user "Board Geometry/Soldermask Bottom")
		(17 "Dwgs.User" user "User.Drawings")
		(19 "Cmts.User" user "User.Comments")
		(21 "Eco1.User" user "User.Eco1")
		(23 "Eco2.User" user "User.Eco2")
		(25 "Edge.Cuts" user "Board Geometry/Outline")
		(27 "Margin" user)
		(31 "F.CrtYd" user "Package Geometry/Place Bound Top")
		(29 "B.CrtYd" user "Package Geometry/Place Bound Bottom")
		(35 "F.Fab" user "Ref Des/Assembly Top")
		(33 "B.Fab" user "Ref Des/Assembly Bottom")
	)
	(footprint ""
		(layer "F.Cu")
		(at 21.463 -102.743 -90)
		(property "Reference" "R747"
			(at 0 0 270)
			(layer "F.SilkS")
			(hide yes)
			(effects
				(font
					(size 1.27 1.27)
				)
			)
		)
		(property "Value" ""
			(at 0 0 270)
			(layer "F.Fab")
			(effects
				(font
					(size 1.27 1.27)
				)
			)
		)
		(duplicate_pad_numbers_are_jumpers no)
		(fp_line
			(start -0.7874 0.4064)
			(end -0.7874 -0.4064)
			(stroke
				(width 0.1524)
				(type default)
			)
			(layer "F.SilkS")
		)
		(fp_line
			(start 0.7874 0.4064)
			(end -0.7874 0.4064)
			(stroke
				(width 0.1524)
				(type default)
			)
			(layer "F.SilkS")
		)
		(fp_line
			(start -0.7874 -0.4064)
			(end 0.7874 -0.4064)
			(stroke
				(width 0.1524)
				(type default)
			)
			(layer "F.SilkS")
		)
		(fp_line
			(start 0.7874 -0.4064)
			(end 0.7874 0.4064)
			(stroke
				(width 0.1524)
				(type default)
			)
			(layer "F.SilkS")
		)
		(fp_line
			(start -0.67945 0.3048)
			(end -0.67945 -0.305054)
			(stroke
				(width 0.1)
				(type default)
			)
			(layer "F.Fab")
		)
		(fp_line
			(start -0.12065 0.3048)
			(end -0.67945 0.3048)
			(stroke
				(width 0.1)
				(type default)
			)
			(layer "F.Fab")
		)
		(fp_line
			(start 0.120396 0.3048)
			(end 0.120396 0.2794)
			(stroke
				(width 0.1)
				(type default)
			)
			(layer "F.Fab")
		)
		(fp_line
			(start 0.67945 0.3048)
			(end 0.120396 0.3048)
			(stroke
				(width 0.1)
				(type default)
			)
			(layer "F.Fab")
		)
		(fp_line
			(start -0.12065 0.2794)
			(end -0.12065 0.3048)
			(stroke
				(width 0.1)
				(type default)
			)
			(layer "F.Fab")
		)
		(fp_line
			(start 0.120396 0.2794)
			(end -0.12065 0.2794)
			(stroke
				(width 0.1)
				(type default)
			)
			(layer "F.Fab")
		)
		(fp_line
			(start -0.12065 -0.2794)
			(end 0.12065 -0.2794)
			(stroke
				(width 0.1)
				(type default)
			)
			(layer "F.Fab")
		)
		(fp_line
			(start 0.12065 -0.2794)
			(end 0.12065 -0.3048)
			(stroke
				(width 0.1)
				(type default)
			)
			(layer "F.Fab")
		)
		(fp_line
			(start 0.12065 -0.3048)
			(end 0.67945 -0.3048)
			(stroke
				(width 0.1)
				(type default)
			)
			(layer "F.Fab")
		)
		(fp_line
			(start 0.67945 -0.3048)
			(end 0.67945 0.3048)
			(stroke
				(width 0.1)
				(type default)
			)
			(layer "F.Fab")
		)
		(fp_line
			(start -0.67945 -0.305054)
			(end -0.12065 -0.305054)
			(stroke
				(width 0.1)
				(type default)
			)
			(layer "F.Fab")
		)
		(fp_line
			(start -0.12065 -0.305054)
			(end -0.12065 -0.2794)
			(stroke
				(width 0.1)
				(type default)
			)
			(layer "F.Fab")
		)
		(pad "1" smd circle
			(at -0.40005 0 270)
			(size 0 0)
			(layers "F.Cu" "F.Mask" "F.Paste")
			(net "FM_BMC_CRASHLOG_TRIG_N")
		)
		(pad "2" smd circle
			(at 0.40005 0 270)
			(size 0 0)
			(layers "F.Cu" "F.Mask" "F.Paste")
			(net "FM_BMC_CRASHLOG_TRIG_R2_N")
		)
	)
	(footprint ""
		(layer "F.Cu")
		(at 43.6626 -34.6456 -90)
		(property "Reference" "R112"
			(at 0 0 270)
			(layer "F.SilkS")
			(hide yes)
			(effects
				(font
					(size 1.27 1.27)
				)
			)
		)
		(property "Value" ""
			(at 0 0 270)
			(layer "F.Fab")
			(effects
				(font
					(size 1.27 1.27)
				)
			)
		)
		(duplicate_pad_numbers_are_jumpers no)
		(fp_line
			(start -0.7874 0.4064)
			(end -0.7874 -0.4064)
			(stroke
				(width 0.1524)
				(type default)
			)
			(layer "F.SilkS")
		)
		(fp_line
			(start 0.7874 0.4064)
			(end -0.7874 0.4064)
			(stroke
				(width 0.1524)
				(type default)
			)
			(layer "F.SilkS")
		)
		(fp_line
			(start -0.7874 -0.4064)
			(end 0.7874 -0.4064)
			(stroke
				(width 0.1524)
				(type default)
			)
			(layer "F.SilkS")
		)
		(fp_line
			(start 0.7874 -0.4064)
			(end 0.7874 0.4064)
			(stroke
				(width 0.1524)
				(type default)
			)
			(layer "F.SilkS")
		)
		(fp_line
			(start -0.67945 0.3048)
			(end -0.67945 -0.305054)
			(stroke
				(width 0.1)
				(type default)
			)
			(layer "F.Fab")
		)
		(fp_line
			(start -0.12065 0.3048)
			(end -0.67945 0.3048)
			(stroke
				(width 0.1)
				(type default)
			)
			(layer "F.Fab")
		)
		(fp_line
			(start 0.120396 0.3048)
			(end 0.120396 0.2794)
			(stroke
				(width 0.1)
				(type default)
			)
			(layer "F.Fab")
		)
		(fp_line
			(start 0.67945 0.3048)
			(end 0.120396 0.3048)
			(stroke
				(width 0.1)
				(type default)
			)
			(layer "F.Fab")
		)
		(fp_line
			(start -0.12065 0.2794)
			(end -0.12065 0.3048)
			(stroke
				(width 0.1)
				(type default)
			)
			(layer "F.Fab")
		)
		(fp_line
			(start 0.120396 0.2794)
			(end -0.12065 0.2794)
			(stroke
				(width 0.1)
				(type default)
			)
			(layer "F.Fab")
		)
		(fp_line
			(start -0.12065 -0.2794)
			(end 0.12065 -0.2794)
			(stroke
				(width 0.1)
				(type default)
			)
			(layer "F.Fab")
		)
		(fp_line
			(start 0.12065 -0.2794)
			(end 0.12065 -0.3048)
			(stroke
				(width 0.1)
				(type default)
			)
			(layer "F.Fab")
		)
		(fp_line
			(start 0.12065 -0.3048)
			(end 0.67945 -0.3048)
			(stroke
				(width 0.1)
				(type default)
			)
			(layer "F.Fab")
		)
		(fp_line
			(start 0.67945 -0.3048)
			(end 0.67945 0.3048)
			(stroke
				(width 0.1)
				(type default)
			)
			(layer "F.Fab")
		)
		(fp_line
			(start -0.67945 -0.305054)
			(end -0.12065 -0.305054)
			(stroke
				(width 0.1)
				(type default)
			)
			(layer "F.Fab")
		)
		(fp_line
			(start -0.12065 -0.305054)
			(end -0.12065 -0.2794)
			(stroke
				(width 0.1)
				(type default)
			)
			(layer "F.Fab")
		)
		(pad "1" smd circle
			(at -0.40005 0 270)
			(size 0 0)
			(layers "F.Cu" "F.Mask" "F.Paste")
			(net "FM_BIOS_DEBUG_EN_R_N")
		)
		(pad "2" smd circle
			(at 0.40005 0 270)
			(size 0 0)
			(layers "F.Cu" "F.Mask" "F.Paste")
			(net "FM_BIOS_DEBUG_EN_N")
		)
	)
)
